FILE_TYPE = CONNECTIVITY;
{Allegro Design Entry HDL 16.6-p007 (v16-6-112F) 10/10/2012}
"PAGE_NUMBER" = 229;
0"NC";
1"PVTT_GHJ\g";
2"GND\g";
3"GND\g";
4"GND\g";
5"GND\g";
6"GND\g";
7"GND\g";
8"PVTT_GHJ\g";
9"GND\g";
10"GND\g";
11"PVDDQ_GHJ\g";
12"P3V3\g";
13"P3V3\g";
14"GND\g";
15"GND\g";
16"PWRGD_PVTT_CPU1";
17"VR_PVTT_GHJ_SNS";
18"PWRGD_PVTT_GHJ_CPU1_R";
19"VR_PVTT_GHJ_VREF";
20"VR_PVTT_GHJ_BIAS";
21"VSENSE_PVDDQ_GHJ_VTT";
22"FM_PVTT_GHJ_EN_R";
23"PWRGD_PVDDQ_GHJ";
%"PVTT_GHJ"
"1","(3475,3650)","0","mstr_symbols","I10";
;
ROOM"VTT_GHJ_VR"
HDL_POWER"PVTT_GHJ"
BODY_TYPE"PLUMBING"
CDS_LIB"mstr_symbols"
BOM_COST"MEM_VRD_PVDDQ_GHJ"
VOLTAGE"0.6V";
"G\NAC"1;
%"RES"
"2","(3450,2025)","0","mstr_discrete","I14";
;
CDS_SEC"1"
CDS_LOCATION"R4G17"
SEC"1"
SEC_TYPE"0402"
BOM_COST"MEM_VRD_VTT_GHJ"
ROOM"VTT_GHJ_PWR_VR"
CDS_LIB"mstr_discrete"
VALUE"10.0K"
LOCATION"R4G17"
TOLERANCE"1%"
PACK_TYPE"0402"
WATTAGE"1/16W"
MATERIAL"CHIP"
PART_NUMBER"G21796-016";
"A"
$PN"1"13;
"B"
$PN"2"18;
%"CAP"
"1","(3825,1625)","2","mstr_discrete","I15";
;
CDS_SEC"1"
SEC_TYPE"0402LF"
BOM_COST"MEM_VRD_VTT_GHJ"
SEC"1"
ROOM"VTT_GHJ_PWR_VR"
CDS_LIB"mstr_discrete"
CDS_LOCATION"C4G13"
LOCATION"C4G13"
VALUE"1000PF"
TOLERANCE"10%"
VOLTAGE"50V"
MATERIAL"X7R"
PACK_TYPE"0402LF"
PART_NUMBER"A36096-046";
"A"
$PN"1"18;
"B"
$PN"2"2;
%"GND"
"1","(3825,1400)","0","mstr_symbols","I16";
;
HDL_POWER"GND"
SIZE"1B"
BODY_TYPE"PLUMBING"
CDS_LIB"mstr_symbols"
VOLTAGE"0.0V";
"A\NAC"2;
%"CAP"
"1","(3925,1075)","0","mstr_discrete","I17";
;
CDS_SEC"1"
SEC_TYPE"0805LF"
SEC"1"
BOM_COST"MEM_VRD_VTT_GHJ"
ROOM"VTT_GHJ_PWR_VR"
CDS_LIB"mstr_discrete"
CDS_LOCATION"C4G20"
PACK_TYPE"0805LF"
LOCATION"C4G20"
TOLERANCE"20%"
VALUE"22UF"
VOLTAGE"4V"
PART_NUMBER"C95333-002"
MATERIAL"X6S";
"A"
$PN"1"8;
"B"
$PN"2"3;
%"GND"
"1","(3925,675)","0","mstr_symbols","I19";
;
HDL_POWER"GND"
BODY_TYPE"PLUMBING"
CDS_LIB"mstr_symbols"
SIZE"1B"
VOLTAGE"0.0V";
"A\NAC"3;
%"CAP"
"1","(2275,850)","0","mstr_discrete","I21";
;
CDS_SEC"1"
SEC"1"
SEC_TYPE"0402"
BOM_COST"MEM_VRD_VTT_GHJ"
ROOM"VTT_GHJ_PWR_VR"
CDS_LOCATION"C4G21"
CDS_LIB"mstr_discrete"
VOLTAGE"16V"
PART_NUMBER"D97712-011"
MATERIAL"X6S"
PACK_TYPE"0402"
TOLERANCE"10%"
VALUE"1.0UF"
LOCATION"C4G21";
"A"
$PN"1"19;
"B"
$PN"2"4;
%"GND"
"1","(2275,600)","0","mstr_symbols","I22";
;
SIZE"1B"
HDL_POWER"GND"
BODY_TYPE"PLUMBING"
VOLTAGE"0.0V"
CDS_LIB"mstr_symbols";
"A\NAC"4;
%"GND"
"1","(1950,600)","0","mstr_symbols","I23";
;
HDL_POWER"GND"
BODY_TYPE"PLUMBING"
CDS_LIB"mstr_symbols"
SIZE"1B"
VOLTAGE"0.0V";
"A\NAC"5;
%"MIC5166"
"1","(1500,1075)","0","mstr_vreg","I24";
;
CDS_SEC"1"
SEC"1"
BOM_COST"MEM_VRD_VTT_GHJ"
SEC_TYPE"DFN"
PACK_TYPE"DFN"
ROOM"VTT_GHJ_PWR_VR"
CDS_LIB"mstr_vreg"
CDS_LMAN_SYM_OUTLINE"-250,350,250,-350"
CDS_LOCATION"EU4G2"
MATERIAL"IC"
LOCATION"EU4G2"
PART_NUMBER"H55101-001";
"THPAD"
$PN"11"5;
"VTT"
$PN"9"8;
"PGND"
$PN"8"5;
"SNS"
$PN"6"17;
"VDDQ"
$PN"4"21;
"PG"
$PN"5"18;
"AGND"
$PN"3"5;
"BIAS"
$PN"2"20;
"VREF"
$PN"1"19;
"VIN"
$PN"10"11;
"EN"
$PN"7"22;
%"CAP"
"1","(425,2375)","0","mstr_discrete","I25";
;
CDS_SEC"1"
SEC"1"
BOM_COST"MEM_VRD_VTT_GHJ"
SEC_TYPE"0603LF"
ROOM"VTT_GHJ_PWR_VR"
CDS_LOCATION"C6U14"
CDS_LIB"mstr_discrete"
MATERIAL"X6S"
VOLTAGE"4V"
PACK_TYPE"0603LF"
TOLERANCE"20%"
VALUE"10UF"
PART_NUMBER"E15431-001"
LOCATION"C6U14";
"A"
$PN"1"11;
"B"
$PN"2"6;
%"GND"
"1","(425,2125)","0","mstr_symbols","I26";
;
HDL_POWER"GND"
SIZE"1B"
CDS_LIB"mstr_symbols"
VOLTAGE"0.0V"
BODY_TYPE"PLUMBING"
BOM_COST"MEM_VRD_VTT_GHJ"
ROOM"VTT_GHJ_PWR_VR";
"A\NAC"6;
%"CAP"
"1","(425,1500)","0","mstr_discrete","I27";
;
CDS_SEC"1"
SEC_TYPE"0402"
BOM_COST"MEM_VRD_VTT_GHJ"
SEC"1"
ROOM"VTT_GHJ_PWR_VR"
CDS_LOCATION"C4G18"
CDS_LIB"mstr_discrete"
MATERIAL"X6S"
VOLTAGE"16V"
PACK_TYPE"0402"
TOLERANCE"10%"
VALUE"1.0UF"
PART_NUMBER"D97712-011"
LOCATION"C4G18";
"A"
$PN"1"20;
"B"
$PN"2"7;
%"GND"
"1","(425,1275)","0","mstr_symbols","I28";
;
HDL_POWER"GND"
CDS_LIB"mstr_symbols"
SIZE"1B"
BODY_TYPE"PLUMBING"
VOLTAGE"0.0V";
"A\NAC"7;
%"CAP"
"1","(0,2350)","0","mstr_discrete","I29";
;
CDS_SEC"1"
SEC"1"
SEC_TYPE"0603LF"
BOM_COST"MEM_VRD_VTT_GHJ"
ROOM"VTT_GHJ_PWR_VR"
CDS_LOCATION"C6U13"
CDS_LIB"mstr_discrete"
PART_NUMBER"E15431-001"
MATERIAL"X6S"
VOLTAGE"4V"
PACK_TYPE"0603LF"
TOLERANCE"20%"
VALUE"10UF"
LOCATION"C6U13";
"A"
$PN"1"11;
"B"
$PN"2"9;
%"PVTT_GHJ"
"1","(5500,1575)","0","mstr_symbols","I3";
;
CDS_LIB"mstr_symbols"
HDL_POWER"PVTT_GHJ"
VOLTAGE"0.6V"
BODY_TYPE"PLUMBING";
"G\NAC"8;
%"GND"
"1","(0,2100)","0","mstr_symbols","I30";
;
SIZE"1B"
HDL_POWER"GND"
CDS_LIB"mstr_symbols"
VOLTAGE"0.0V"
BOM_COST"MEM_VRD_VTT_GHJ"
BODY_TYPE"PLUMBING"
ROOM"VTT_GHJ_PWR_VR";
"A\NAC"9;
%"RES"
"1","(100,1775)","0","mstr_discrete","I32";
;
CDS_SEC"1"
ROOM"VTT_GHJ_PWR_VR"
CDS_LOCATION"R6U7"
SEC"1"
SEC_TYPE"0402"
BOM_COST"MEM_VRD_VTT_GHJ"
CDS_LIB"mstr_discrete"
LOCATION"R6U7"
PACK_TYPE"0402"
TOLERANCE"5%"
MATERIAL"CHIP"
WATTAGE"1/16W"
VALUE"0.0"
PART_NUMBER"G21497-005";
"B"
$PN"2"20;
"A"
$PN"1"12;
%"RES"
"2","(-350,675)","2","mstr_discrete","I34";
;
CDS_SEC"1"
ROOM"VTT_GHJ_PWR_VR"
CDS_LOCATION"R6U3"
SEC"1"
SEC_TYPE"0402"
BOM_COST"MEM_VRD_VTT_GHJ"
CDS_LIB"mstr_discrete"
LOCATION"R6U3"
VALUE"1.0M"
TOLERANCE"1%"
PACK_TYPE"0402"
WATTAGE"1/16W"
PART_NUMBER"G21796-021"
MATERIAL"EMPTY";
"A"
$PN"1"12;
"B"
$PN"2"22;
%"RES"
"1","(-575,150)","0","mstr_discrete","I35";
;
CDS_SEC"1"
ROOM"VTT_GHJ_PWR_VR"
BOM_COST"MEM_VRD_VTT_GHJ"
SEC_TYPE"0402"
SEC"1"
CDS_LOCATION"R4G16"
CDS_LIB"mstr_discrete"
PART_NUMBER"G21497-005"
LOCATION"R4G16"
VALUE"0.0"
TOLERANCE"5%"
WATTAGE"1/16W"
MATERIAL"CHIP"
PACK_TYPE"0402";
"B"
$PN"2"22;
"A"
$PN"1"23;
%"CAP"
"1","(-400,-375)","2","mstr_discrete","I36";
;
CDS_SEC"1"
ROOM"VTT_GHJ_PWR_VR"
SEC"1"
BOM_COST"MEM_VRD_VTT_GHJ"
SEC_TYPE"0402LF"
CDS_LOCATION"C4G12"
CDS_LIB"mstr_discrete"
PART_NUMBER"A36096-046"
VOLTAGE"50V"
PACK_TYPE"0402LF"
TOLERANCE"10%"
VALUE"1000PF"
LOCATION"C4G12"
MATERIAL"EMPTY";
"A"
$PN"1"22;
"B"
$PN"2"10;
%"GND"
"1","(-400,-600)","0","mstr_symbols","I37";
;
HDL_POWER"GND"
BODY_TYPE"PLUMBING"
SIZE"1B"
CDS_LIB"mstr_symbols"
VOLTAGE"0.0V";
"A\NAC"10;
%"PVDDQ_GHJ"
"1","(-1475,2800)","0","mstr_symbols","I38";
;
VOLTAGE"1.2V"
CDS_LIB"mstr_symbols"
BODY_TYPE"PLUMBING"
HDL_POWER"PVDDQ_GHJ";
"G\NAC"11;
%"RES"
"2","(-775,1575)","1","mstr_discrete","I39";
;
CDS_SEC"1"
ROOM"VTT_GHJ_PWR_VR"
NO_XNET_CONNECTION"1"
CDS_LOCATION"R6U6"
SEC"1"
SEC_TYPE"0402"
BOM_COST"MEM_VRD_VTT_GHJ"
CDS_LIB"mstr_discrete"
MATERIAL"CHIP"
PACK_TYPE"0402"
LOCATION"R6U6"
WATTAGE"1/16W"
TOLERANCE"5%"
VALUE"0.0"
PART_NUMBER"G21497-005";
"A"
$PN"1"11;
"B"
$PN"2"21;
%"P3V3"
"1","(-525,2075)","0","mstr_symbols","I42";
;
CDS_LIB"mstr_symbols"
SIZE"1B"
VOLTAGE"3.3V"
BODY_TYPE"PLUMBING"
HDL_POWER"P3V3";
"G\NAC"12;
%"P3V3"
"1","(3450,2275)","0","mstr_symbols","I43";
;
CDS_LIB"mstr_symbols"
SIZE"1B"
VOLTAGE"3.3V"
BODY_TYPE"PLUMBING"
HDL_POWER"P3V3";
"G\NAC"13;
%"GND"
"1","(275,775)","0","mstr_symbols","I45";
;
HDL_POWER"GND"
CDS_LIB"mstr_symbols"
SIZE"1B"
BODY_TYPE"PLUMBING"
VOLTAGE"0.0V";
"A\NAC"14;
%"CAP"
"1","(275,1000)","0","mstr_discrete","I46";
;
CDS_SEC"1"
ROOM"VTT_GHJ_PWR_VR"
SEC"1"
SEC_TYPE"0603"
CDS_LOCATION"C6U11"
CDS_LIB"mstr_discrete"
LOCATION"C6U11"
VALUE"4.7UF"
VOLTAGE"6.3V"
PART_NUMBER"E15431-003"
MATERIAL"X6S"
TOLERANCE"10%"
PACK_TYPE"0603";
"A"
$PN"1"21;
"B"
$PN"2"14;
%"CAP_A"
"1","(3475,3375)","0","dev_discrete","I47";
;
SEC"1"
SEC_TYPE"0603V"
CDS_SEC"1"
CDS_LOCATION"C2F2"
CDS_LIB"dev_discrete"
MATERIAL"X5R"
PACK_TYPE"0603V"
TOLERANCE"20%"
VALUE"47UF"
PART_NUMBER"602433-106"
LOCATION"C2F2"
VOLTAGE"4V";
"B"
$PN"2"15;
"A"
$PN"1"1;
%"CAP_A"
"1","(3825,3375)","0","dev_discrete","I48";
;
SEC"1"
SEC_TYPE"0603V"
CDS_SEC"1"
CDS_LOCATION"C8T3"
CDS_LIB"dev_discrete"
PART_NUMBER"602433-106"
VOLTAGE"4V"
PACK_TYPE"0603V"
TOLERANCE"20%"
VALUE"47UF"
LOCATION"C8T3"
MATERIAL"X5R";
"B"
$PN"2"15;
"A"
$PN"1"1;
%"CAP_A"
"1","(4225,3375)","0","dev_discrete","I49";
;
SEC"1"
SEC_TYPE"0603V"
CDS_SEC"1"
CDS_LIB"dev_discrete"
CDS_LOCATION"C8U10"
MATERIAL"X5R"
PACK_TYPE"0603V"
TOLERANCE"20%"
VALUE"47UF"
PART_NUMBER"602433-106"
LOCATION"C8U10"
VOLTAGE"4V";
"B"
$PN"2"15;
"A"
$PN"1"1;
%"RES"
"1","(4025,1825)","0","mstr_discrete","I51";
;
CDS_SEC"1"
SEC"1"
SEC_TYPE"0402"
CDS_LIB"mstr_discrete"
CDS_LOCATION"R4G15"
PACK_TYPE"0402"
MATERIAL"CHIP"
PART_NUMBER"G21796-074"
LOCATION"R4G15"
VALUE"33.2"
TOLERANCE"1%"
WATTAGE"1/16W";
"B"
$PN"2"16;
"A"
$PN"1"18;
%"RES"
"1","(4775,1000)","1","mstr_discrete","I52";
;
$SEC"1"
CDS_SEC"1"
CDS_LIB"mstr_discrete"
CDS_LOCATION"R6U8"
PACK_TYPE"0402"
MATERIAL"CHIP"
TOLERANCE"1.0%"
PART_NUMBER"G21796-208"
LOCATION"R6U8"
WATTAGE"1/16W"
VALUE"51.1";
"B"
$PN"2"8;
"A"
$PN"1"3;
%"SHUNT"
"1","(4925,25)","0","mstr_misc","I53";
;
CDS_SEC"1"
CDS_LOCATION"SH8U1"
SEC_TYPE"SH0201"
CDS_LIB"mstr_misc"
SEC"1"
PACK_TYPE"SH0201"
PIN_SHORT"A:B"
MATERIAL"EMPTY"
LOCATION"SH8U1"
PART_NUMBER"N_A";
"A"
$PN"1"17;
"B"
$PN"2"8;
%"GND"
"1","(4350,3025)","0","mstr_symbols","I7";
;
HDL_POWER"GND"
BODY_TYPE"PLUMBING"
SIZE"1B"
CDS_LIB"mstr_symbols"
VOLTAGE"0.0V"
BOM_COST"MEM_VRD_PVDDQ_GHJ"
ROOM"VTT_GHJ_VR";
"A\NAC"15;
END.
